(kicad_pcb
	(version 20260206)
	(generator "pcbnew")
	(generator_version "10.0")
	(general
		(thickness 1.6)
		(legacy_teardrops no)
	)
	(paper "A4")
	(title_block
		(title "03242023_DA0F0TMBIJ0_F0T_Motherboard_J_brd_V01_OCP.brd")
		(comment 1 "Grand Teton / footprint 1682 of 6105 (U1), pads 750-854 of 4677")
	)
	(layers
		(0 "F.Cu" signal "TOP")
		(4 "In1.Cu" signal "GND")
		(6 "In2.Cu" signal "IN1")
		(8 "In3.Cu" signal "GND1")
		(10 "In4.Cu" signal "IN2")
		(12 "In5.Cu" signal "GND2")
		(14 "In6.Cu" signal "IN3")
		(16 "In7.Cu" signal "GND3")
		(18 "In8.Cu" signal "VCC")
		(20 "In9.Cu" signal "VCC1")
		(22 "In10.Cu" signal "GND4")
		(24 "In11.Cu" signal "IN4")
		(26 "In12.Cu" signal "GND5")
		(28 "In13.Cu" signal "IN5")
		(30 "In14.Cu" signal "GND6")
		(32 "In15.Cu" signal "IN6")
		(34 "In16.Cu" signal "GND7")
		(2 "B.Cu" signal "BOTTOM")
		(9 "F.Adhes" user "F.Adhesive")
		(11 "B.Adhes" user "B.Adhesive")
		(13 "F.Paste" user "Package Geometry/Pastemask Top")
		(15 "B.Paste" user "Package Geometry/Pastemask Bottom")
		(5 "F.SilkS" user "Ref Des/Silkscreen Top")
		(7 "B.SilkS" user "Ref Des/Silkscreen Bottom")
		(1 "F.Mask" user "Board Geometry/Soldermask Top")
		(3 "B.Mask" user "Board Geometry/Soldermask Bottom")
		(17 "Dwgs.User" user "User.Drawings")
		(19 "Cmts.User" user "User.Comments")
		(21 "Eco1.User" user "User.Eco1")
		(23 "Eco2.User" user "User.Eco2")
		(25 "Edge.Cuts" user "Board Geometry/Outline")
		(27 "Margin" user)
		(31 "F.CrtYd" user "Package Geometry/Place Bound Top")
		(29 "B.CrtYd" user "Package Geometry/Place Bound Bottom")
		(35 "F.Fab" user "Ref Des/Assembly Top")
		(33 "B.Fab" user "Ref Des/Assembly Bottom")
	)
	(footprint ""
		(layer "F.Cu")
		(at 111.93018 -251.76988 90)
		(property "Reference" "U1"
			(at -74.913236 41.548812 0)
			(unlocked yes)
			(layer "F.SilkS")
			(effects
				(font
					(size 1.6002 1.1938)
					(thickness 0.1524)
				)
				(justify left)
			)
		)
		(property "Value" ""
			(at 0 0 90)
			(layer "F.Fab")
			(effects
				(font
					(size 1.27 1.27)
				)
			)
		)
		(duplicate_pad_numbers_are_jumpers no)
		(pad "AU7" smd circle
			(at -32.541718 -10.157714 270)
			(size 0.4318 0.4318)
			(layers "F.Cu" "F.Mask" "F.Paste")
			(net "PVCCD_HV_CPU1")
		)
		(pad "AU9" smd circle
			(at -30.914086 -10.157714 270)
			(size 0.4318 0.4318)
			(layers "F.Cu" "F.Mask" "F.Paste")
			(net "P5E_CPU1_PE0_RX_DN<13>")
		)
		(pad "AU11" smd circle
			(at -29.2862 -10.157714 270)
			(size 0.4318 0.4318)
			(layers "F.Cu" "F.Mask" "F.Paste")
			(net "VSENSE_PVCCFA_EHV_CPU1_DP")
		)
		(pad "AU13" smd circle
			(at -27.658314 -10.157714 270)
			(size 0.4318 0.4318)
			(layers "F.Cu" "F.Mask" "F.Paste")
			(net "P5E_CPU1_PE0_TX_DN<12>")
		)
		(pad "AU15" smd circle
			(at -26.030682 -10.157714 270)
			(size 0.4318 0.4318)
			(layers "F.Cu" "F.Mask" "F.Paste")
			(net "PVCCFA_EHV_FIVRA_CPU1")
		)
		(pad "AU17" smd circle
			(at -24.402796 -10.157714 270)
			(size 0.4318 0.4318)
			(layers "F.Cu" "F.Mask" "F.Paste")
			(net "PU_CPU1_FRMAGENT")
		)
		(pad "AU19" smd circle
			(at -22.77491 -10.157714 270)
			(size 0.4318 0.4318)
			(layers "F.Cu" "F.Mask" "F.Paste")
			(net "H_CPU1_PROCHOT_LVC1_N")
		)
		(pad "AU21" smd circle
			(at -21.147278 -10.157714 270)
			(size 0.4318 0.4318)
			(layers "F.Cu" "F.Mask" "F.Paste")
			(net "H_CPU1_MEMHOT_IN_LVC1_N")
		)
		(pad "AU23" smd circle
			(at -19.519392 -10.157714 270)
			(size 0.4318 0.4318)
			(layers "F.Cu" "F.Mask" "F.Paste")
			(net "PU_CPU1_SAFE_MODE_BOOT")
		)
		(pad "AU25" smd circle
			(at -17.89176 -10.157714 270)
			(size 0.4318 0.4318)
			(layers "F.Cu" "F.Mask" "F.Paste")
			(net "CPU1_RSVD<6>")
		)
		(pad "AU27" smd circle
			(at -16.263874 -10.157714 270)
			(size 0.4318 0.4318)
			(layers "F.Cu" "F.Mask" "F.Paste")
			(net "GND")
		)
		(pad "AU29" smd circle
			(at -14.635988 -10.157714 270)
			(size 0.4318 0.4318)
			(layers "F.Cu" "F.Mask" "F.Paste")
			(net "CLK_100M_DB2000_CPU1_BCLK2_DN")
		)
		(pad "AU31" smd circle
			(at -13.008356 -10.157714 270)
			(size 0.4318 0.4318)
			(layers "F.Cu" "F.Mask" "F.Paste")
			(net "GND")
		)
		(pad "AU33" smd circle
			(at -11.380724 -10.157714 270)
			(size 0.4318 0.4318)
			(layers "F.Cu" "F.Mask" "F.Paste")
			(net "NC_CPU1_DDR23_VIEWDIG1")
		)
		(pad "AU35" smd circle
			(at -9.752838 -10.157714 270)
			(size 0.4318 0.4318)
			(layers "F.Cu" "F.Mask" "F.Paste")
			(net "PVCCD_HV_CPU1")
		)
		(pad "AU37" smd circle
			(at -8.124952 -10.157714 270)
			(size 0.4318 0.4318)
			(layers "F.Cu" "F.Mask" "F.Paste")
			(net "GND")
		)
		(pad "AU39" smd circle
			(at -6.49732 -10.157714 270)
			(size 0.4318 0.4318)
			(layers "F.Cu" "F.Mask" "F.Paste")
			(net "GND")
		)
		(pad "AU41" smd circle
			(at -4.869434 -10.157714 270)
			(size 0.4318 0.4318)
			(layers "F.Cu" "F.Mask" "F.Paste")
			(net "GND")
		)
		(pad "AU43" smd circle
			(at -3.241802 -10.157714 270)
			(size 0.4318 0.4318)
			(layers "F.Cu" "F.Mask" "F.Paste")
			(net "M_A_CPU1_SA_RSP<1>")
		)
		(pad "AU45" smd circle
			(at -1.613916 -10.157714 270)
			(size 0.4318 0.4318)
			(layers "F.Cu" "F.Mask" "F.Paste")
			(net "GND")
		)
		(pad "AU48" smd circle
			(at 2.427732 -10.047732 270)
			(size 0.4318 0.4318)
			(layers "F.Cu" "F.Mask" "F.Paste")
			(net "GND")
		)
		(pad "AU50" smd circle
			(at 4.055618 -10.047732 270)
			(size 0.4318 0.4318)
			(layers "F.Cu" "F.Mask" "F.Paste")
			(net "RST_CPU1_DRAM_AB_N")
		)
		(pad "AU52" smd circle
			(at 5.68325 -10.047732 270)
			(size 0.4318 0.4318)
			(layers "F.Cu" "F.Mask" "F.Paste")
			(net "TP_CPU1_SPARE5")
		)
		(pad "AU54" smd circle
			(at 7.311136 -10.047732 270)
			(size 0.4318 0.4318)
			(layers "F.Cu" "F.Mask" "F.Paste")
			(net "PVCCD_HV_CPU1")
		)
		(pad "AU56" smd circle
			(at 8.939022 -10.047732 270)
			(size 0.4318 0.4318)
			(layers "F.Cu" "F.Mask" "F.Paste")
			(net "NC_CPU1_DDR01_VIEWDIG1")
		)
		(pad "AU58" smd circle
			(at 10.566654 -10.047732 270)
			(size 0.4318 0.4318)
			(layers "F.Cu" "F.Mask" "F.Paste")
			(net "NC_CPU1_DDR01_VIEWDIG0")
		)
		(pad "AU60" smd circle
			(at 12.19454 -10.047732 270)
			(size 0.4318 0.4318)
			(layers "F.Cu" "F.Mask" "F.Paste")
			(net "PVCCFA_EHV_CPU1")
		)
		(pad "AU62" smd circle
			(at 13.822426 -10.047732 270)
			(size 0.4318 0.4318)
			(layers "F.Cu" "F.Mask" "F.Paste")
			(net "NC_SPI_CPU1_NCM_CLK")
		)
		(pad "AU64" smd circle
			(at 15.450058 -10.047732 270)
			(size 0.4318 0.4318)
			(layers "F.Cu" "F.Mask" "F.Paste")
			(net "NC_ESPI_IBL_CPU1_IO2")
		)
		(pad "AU66" smd circle
			(at 17.07769 -10.047732 270)
			(size 0.4318 0.4318)
			(layers "F.Cu" "F.Mask" "F.Paste")
			(net "NC_CPU1_PE4_APROBE<1>")
		)
		(pad "AU68" smd circle
			(at 18.705576 -10.047732 270)
			(size 0.4318 0.4318)
			(layers "F.Cu" "F.Mask" "F.Paste")
			(net "NC_CPU1_UPI2_APROBE<0>")
		)
		(pad "AU70" smd circle
			(at 20.333462 -10.047732 270)
			(size 0.4318 0.4318)
			(layers "F.Cu" "F.Mask" "F.Paste")
			(net "GND")
		)
		(pad "AU72" smd circle
			(at 21.961094 -10.047732 270)
			(size 0.4318 0.4318)
			(layers "F.Cu" "F.Mask" "F.Paste")
			(net "GND")
		)
		(pad "AU74" smd circle
			(at 23.58898 -10.047732 270)
			(size 0.4318 0.4318)
			(layers "F.Cu" "F.Mask" "F.Paste")
			(net "GND")
		)
		(pad "AU76" smd circle
			(at 25.216612 -10.047732 270)
			(size 0.4318 0.4318)
			(layers "F.Cu" "F.Mask" "F.Paste")
			(net "GND")
		)
		(pad "AU78" smd circle
			(at 26.844498 -10.047732 270)
			(size 0.4318 0.4318)
			(layers "F.Cu" "F.Mask" "F.Paste")
			(net "UPI_CPU1_CPU0_P2P2_DN<11>")
		)
		(pad "AU80" smd circle
			(at 28.472384 -10.047732 270)
			(size 0.4318 0.4318)
			(layers "F.Cu" "F.Mask" "F.Paste")
			(net "GND")
		)
		(pad "AU82" smd circle
			(at 30.100016 -10.047732 270)
			(size 0.4318 0.4318)
			(layers "F.Cu" "F.Mask" "F.Paste")
			(net "UPI_CPU1_CPU0_P2P2_DP<16>")
		)
		(pad "AU84" smd circle
			(at 31.727902 -10.047732 270)
			(size 0.4318 0.4318)
			(layers "F.Cu" "F.Mask" "F.Paste")
			(net "GND")
		)
		(pad "AU86" smd circle
			(at 33.355534 -10.047732 270)
			(size 0.4318 0.4318)
			(layers "F.Cu" "F.Mask" "F.Paste")
			(net "P5E_CPU1_PE4_TX_DN<13>")
		)
		(pad "AU88" smd circle
			(at 34.98342 -10.047732 270)
			(size 0.4318 0.4318)
			(layers "F.Cu" "F.Mask" "F.Paste")
			(net "GND")
		)
		(pad "AU90" smd circle
			(at 36.611306 -10.047732 270)
			(size 0.4318 0.4318)
			(layers "F.Cu" "F.Mask" "F.Paste")
			(net "P5E_CPU1_PE4_RX_DP<13>")
		)
		(pad "AV2" smd circle
			(at -36.611306 -9.688068 270)
			(size 0.4318 0.4318)
			(layers "F.Cu" "F.Mask" "F.Paste")
			(net "UPI_CPU1_CPU0_P0P1_DP<14>")
		)
		(pad "AV4" smd circle
			(at -34.98342 -9.688068 270)
			(size 0.4318 0.4318)
			(layers "F.Cu" "F.Mask" "F.Paste")
			(net "GND")
		)
		(pad "AV6" smd circle
			(at -33.355534 -9.688068 270)
			(size 0.4318 0.4318)
			(layers "F.Cu" "F.Mask" "F.Paste")
			(net "UPI_CPU0_CPU1_P1P0_DN<14>")
		)
		(pad "AV8" smd circle
			(at -31.727902 -9.688068 270)
			(size 0.4318 0.4318)
			(layers "F.Cu" "F.Mask" "F.Paste")
			(net "GND")
		)
		(pad "AV10" smd circle
			(at -30.100016 -9.688068 270)
			(size 0.4318 0.4318)
			(layers "F.Cu" "F.Mask" "F.Paste")
			(net "P5E_CPU1_PE0_RX_DN<14>")
		)
		(pad "AV12" smd circle
			(at -28.472384 -9.688068 270)
			(size 0.4318 0.4318)
			(layers "F.Cu" "F.Mask" "F.Paste")
			(net "GND")
		)
		(pad "AV14" smd circle
			(at -26.844498 -9.688068 270)
			(size 0.4318 0.4318)
			(layers "F.Cu" "F.Mask" "F.Paste")
			(net "P5E_CPU1_PE0_TX_DN<13>")
		)
		(pad "AV16" smd circle
			(at -25.216612 -9.688068 270)
			(size 0.4318 0.4318)
			(layers "F.Cu" "F.Mask" "F.Paste")
			(net "GND")
		)
		(pad "AV18" smd circle
			(at -23.58898 -9.688068 270)
			(size 0.4318 0.4318)
			(layers "F.Cu" "F.Mask" "F.Paste")
			(net "H_CPU1_NMI_LVC1_N")
		)
		(pad "AV20" smd circle
			(at -21.961094 -9.688068 270)
			(size 0.4318 0.4318)
			(layers "F.Cu" "F.Mask" "F.Paste")
			(net "PWRGD_CPU1_LVC1")
		)
		(pad "AV22" smd circle
			(at -20.333462 -9.688068 270)
			(size 0.4318 0.4318)
			(layers "F.Cu" "F.Mask" "F.Paste")
			(net "H_CPU1_PREQ_QS_GTL_R_N")
		)
		(pad "AV24" smd circle
			(at -18.705576 -9.688068 270)
			(size 0.4318 0.4318)
			(layers "F.Cu" "F.Mask" "F.Paste")
			(net "H_CPU1_MEMTRIP_LVC1_R_N")
		)
		(pad "AV26" smd circle
			(at -17.07769 -9.688068 270)
			(size 0.4318 0.4318)
			(layers "F.Cu" "F.Mask" "F.Paste")
			(net "CPU1_RSVD<15>")
		)
		(pad "AV28" smd circle
			(at -15.450058 -9.688068 270)
			(size 0.4318 0.4318)
			(layers "F.Cu" "F.Mask" "F.Paste")
			(net "CLK_100M_DB2000_CPU1_BCLK2_DP")
		)
		(pad "AV30" smd circle
			(at -13.822426 -9.688068 270)
			(size 0.4318 0.4318)
			(layers "F.Cu" "F.Mask" "F.Paste")
			(net "CLK_100M_DB2000_CPU1_BCLK0_DP")
		)
		(pad "AV32" smd circle
			(at -12.19454 -9.688068 270)
			(size 0.4318 0.4318)
			(layers "F.Cu" "F.Mask" "F.Paste")
			(net "NC_CPU1_DDR23_VIEWDIG0")
		)
		(pad "AV34" smd circle
			(at -10.566654 -9.688068 270)
			(size 0.4318 0.4318)
			(layers "F.Cu" "F.Mask" "F.Paste")
			(net "PVCCD_HV_CPU1")
		)
		(pad "AV36" smd circle
			(at -8.939022 -9.688068 270)
			(size 0.4318 0.4318)
			(layers "F.Cu" "F.Mask" "F.Paste")
			(net "PVCCD_HV_CPU1")
		)
		(pad "AV38" smd circle
			(at -7.311136 -9.688068 270)
			(size 0.4318 0.4318)
			(layers "F.Cu" "F.Mask" "F.Paste")
			(net "NC_CPU1_THERMADC")
		)
		(pad "AV40" smd circle
			(at -5.68325 -9.688068 270)
			(size 0.4318 0.4318)
			(layers "F.Cu" "F.Mask" "F.Paste")
			(net "NC_CPU1_THERMADA")
		)
		(pad "AV42" smd circle
			(at -4.055618 -9.688068 270)
			(size 0.4318 0.4318)
			(layers "F.Cu" "F.Mask" "F.Paste")
			(net "M_A_CPU1_SB_RSP<1>")
		)
		(pad "AV44" smd circle
			(at -2.427732 -9.688068 270)
			(size 0.4318 0.4318)
			(layers "F.Cu" "F.Mask" "F.Paste")
			(net "M_A_CPU1_SB_RSP<0>")
		)
		(pad "AV47" smd circle
			(at 1.613916 -9.578086 270)
			(size 0.4318 0.4318)
			(layers "F.Cu" "F.Mask" "F.Paste")
			(net "M_D_CPU1_ALERT_N")
		)
		(pad "AV49" smd circle
			(at 3.241802 -9.578086 270)
			(size 0.4318 0.4318)
			(layers "F.Cu" "F.Mask" "F.Paste")
			(net "M_B_CPU1_ALERT_N")
		)
		(pad "AV51" smd circle
			(at 4.869434 -9.578086 270)
			(size 0.4318 0.4318)
			(layers "F.Cu" "F.Mask" "F.Paste")
			(net "RST_CPU1_DRAM_CD_N")
		)
		(pad "AV53" smd circle
			(at 6.49732 -9.578086 270)
			(size 0.4318 0.4318)
			(layers "F.Cu" "F.Mask" "F.Paste")
			(net "PVCCD_HV_CPU1")
		)
		(pad "AV55" smd circle
			(at 8.124952 -9.578086 270)
			(size 0.4318 0.4318)
			(layers "F.Cu" "F.Mask" "F.Paste")
			(net "PVCCD_HV_CPU1")
		)
		(pad "AV57" smd circle
			(at 9.752838 -9.578086 270)
			(size 0.4318 0.4318)
			(layers "F.Cu" "F.Mask" "F.Paste")
			(net "FM_CPU_FBRK_DEBUG_R_N")
		)
		(pad "AV59" smd circle
			(at 11.380724 -9.578086 270)
			(size 0.4318 0.4318)
			(layers "F.Cu" "F.Mask" "F.Paste")
			(net "TP_EV_CPU1_EXT_BGREF")
		)
		(pad "AV61" smd circle
			(at 13.008356 -9.578086 270)
			(size 0.4318 0.4318)
			(layers "F.Cu" "F.Mask" "F.Paste")
			(net "PVCCFA_EHV_CPU1")
		)
		(pad "AV63" smd circle
			(at 14.635988 -9.578086 270)
			(size 0.4318 0.4318)
			(layers "F.Cu" "F.Mask" "F.Paste")
			(net "NC_SPI_S3M_CPU1_CS1_LVC1_R_N")
		)
		(pad "AV65" smd circle
			(at 16.263874 -9.578086 270)
			(size 0.4318 0.4318)
			(layers "F.Cu" "F.Mask" "F.Paste")
			(net "NC_CPU1_MDFI_DIE01_EW0")
		)
		(pad "AV67" smd circle
			(at 17.89176 -9.578086 270)
			(size 0.4318 0.4318)
			(layers "F.Cu" "F.Mask" "F.Paste")
			(net "NC_CPU1_PE4_APROBE<0>")
		)
		(pad "AV69" smd circle
			(at 19.519392 -9.578086 270)
			(size 0.4318 0.4318)
			(layers "F.Cu" "F.Mask" "F.Paste")
			(net "FM_S3M_CPU1_LVC1_GPIO_2")
		)
		(pad "AV71" smd circle
			(at 21.147278 -9.578086 270)
			(size 0.4318 0.4318)
			(layers "F.Cu" "F.Mask" "F.Paste")
			(net "FM_S3M_CPU1_LVC1_GPIO_1")
		)
		(pad "AV73" smd circle
			(at 22.77491 -9.578086 270)
			(size 0.4318 0.4318)
			(layers "F.Cu" "F.Mask" "F.Paste")
			(net "UPI_CPU0_CPU1_P2P2_DN<13>")
		)
		(pad "AV75" smd circle
			(at 24.402796 -9.578086 270)
			(size 0.4318 0.4318)
			(layers "F.Cu" "F.Mask" "F.Paste")
			(net "UPI_CPU0_CPU1_P2P2_DP<16>")
		)
		(pad "AV77" smd circle
			(at 26.030682 -9.578086 270)
			(size 0.4318 0.4318)
			(layers "F.Cu" "F.Mask" "F.Paste")
			(net "GND")
		)
		(pad "AV79" smd circle
			(at 27.658314 -9.578086 270)
			(size 0.4318 0.4318)
			(layers "F.Cu" "F.Mask" "F.Paste")
			(net "UPI_CPU1_CPU0_P2P2_DP<11>")
		)
		(pad "AV81" smd circle
			(at 29.2862 -9.578086 270)
			(size 0.4318 0.4318)
			(layers "F.Cu" "F.Mask" "F.Paste")
			(net "UPI_CPU1_CPU0_P2P2_DN<16>")
		)
		(pad "AV83" smd circle
			(at 30.914086 -9.578086 270)
			(size 0.4318 0.4318)
			(layers "F.Cu" "F.Mask" "F.Paste")
			(net "UPI_CPU1_CPU0_P2P2_DP<15>")
		)
		(pad "AV85" smd circle
			(at 32.541718 -9.578086 270)
			(size 0.4318 0.4318)
			(layers "F.Cu" "F.Mask" "F.Paste")
			(net "P5E_CPU1_PE4_TX_DP<13>")
		)
		(pad "AV87" smd circle
			(at 34.169604 -9.578086 270)
			(size 0.4318 0.4318)
			(layers "F.Cu" "F.Mask" "F.Paste")
			(net "GND")
		)
		(pad "AV89" smd circle
			(at 35.797236 -9.578086 270)
			(size 0.4318 0.4318)
			(layers "F.Cu" "F.Mask" "F.Paste")
			(net "P5E_CPU1_PE4_RX_DN<13>")
		)
		(pad "AV91" smd oval
			(at 37.425122 -9.578086)
			(size 0.381 0.4826)
			(drill
				(offset 0 -0.0508)
			)
			(layers "F.Cu" "F.Mask" "F.Paste")
			(net "GND")
		)
		(pad "AW1" smd oval
			(at -37.425122 -9.217914 180)
			(size 0.381 0.4826)
			(drill
				(offset 0 -0.0508)
			)
			(layers "F.Cu" "F.Mask" "F.Paste")
			(net "GND")
		)
		(pad "AW3" smd circle
			(at -35.797236 -9.217914 270)
			(size 0.4318 0.4318)
			(layers "F.Cu" "F.Mask" "F.Paste")
			(net "UPI_CPU1_CPU0_P0P1_DP<15>")
		)
		(pad "AW5" smd circle
			(at -34.169604 -9.217914 270)
			(size 0.4318 0.4318)
			(layers "F.Cu" "F.Mask" "F.Paste")
			(net "GND")
		)
		(pad "AW7" smd circle
			(at -32.541718 -9.217914 270)
			(size 0.4318 0.4318)
			(layers "F.Cu" "F.Mask" "F.Paste")
			(net "UPI_CPU0_CPU1_P1P0_DP<14>")
		)
		(pad "AW9" smd circle
			(at -30.914086 -9.217914 270)
			(size 0.4318 0.4318)
			(layers "F.Cu" "F.Mask" "F.Paste")
			(net "GND")
		)
		(pad "AW11" smd circle
			(at -29.2862 -9.217914 270)
			(size 0.4318 0.4318)
			(layers "F.Cu" "F.Mask" "F.Paste")
			(net "P5E_CPU1_PE0_RX_DP<14>")
		)
		(pad "AW13" smd circle
			(at -27.658314 -9.217914 270)
			(size 0.4318 0.4318)
			(layers "F.Cu" "F.Mask" "F.Paste")
			(net "GND")
		)
		(pad "AW15" smd circle
			(at -26.030682 -9.217914 270)
			(size 0.4318 0.4318)
			(layers "F.Cu" "F.Mask" "F.Paste")
			(net "P5E_CPU1_PE0_TX_DP<13>")
		)
		(pad "AW17" smd circle
			(at -24.402796 -9.217914 270)
			(size 0.4318 0.4318)
			(layers "F.Cu" "F.Mask" "F.Paste")
			(net "PD_CPU1_DMIMODE_OVERRIDE")
		)
		(pad "AW19" smd circle
			(at -22.77491 -9.217914 270)
			(size 0.4318 0.4318)
			(layers "F.Cu" "F.Mask" "F.Paste")
			(net "TP_FM_WAKE_CPU1_N")
		)
		(pad "AW21" smd circle
			(at -21.147278 -9.217914 270)
			(size 0.4318 0.4318)
			(layers "F.Cu" "F.Mask" "F.Paste")
			(net "GND")
		)
		(pad "AW23" smd circle
			(at -19.519392 -9.217914 270)
			(size 0.4318 0.4318)
			(layers "F.Cu" "F.Mask" "F.Paste")
			(net "GND")
		)
		(pad "AW25" smd circle
			(at -17.89176 -9.217914 270)
			(size 0.4318 0.4318)
			(layers "F.Cu" "F.Mask" "F.Paste")
			(net "GND")
		)
		(pad "AW60" smd circle
			(at 12.19454 -9.107932 270)
			(size 0.4318 0.4318)
			(layers "F.Cu" "F.Mask" "F.Paste")
			(net "PVCCFA_EHV_CPU1")
		)
		(pad "AW62" smd circle
			(at 13.822426 -9.107932 270)
			(size 0.4318 0.4318)
			(layers "F.Cu" "F.Mask" "F.Paste")
			(net "GND")
		)
		(pad "AW64" smd circle
			(at 15.450058 -9.107932 270)
			(size 0.4318 0.4318)
			(layers "F.Cu" "F.Mask" "F.Paste")
			(net "NC_SPI_S3M_CPU1_IO1_LVC1_R")
		)
		(pad "AW66" smd circle
			(at 17.07769 -9.107932 270)
			(size 0.4318 0.4318)
			(layers "F.Cu" "F.Mask" "F.Paste")
			(net "GND")
		)
		(pad "AW68" smd circle
			(at 18.705576 -9.107932 270)
			(size 0.4318 0.4318)
			(layers "F.Cu" "F.Mask" "F.Paste")
			(net "GND")
		)
	)
)
